(kicad_pcb
	(version 20260206)
	(generator "pcbnew")
	(generator_version "10.0")
	(general
		(thickness 1.6)
		(legacy_teardrops no)
	)
	(paper "A4")
	(title_block
		(title "Bryce Canyon_IOM_M2_16342-2_OCP.brd")
		(comment 1 "Bryce Canyon / footprints 566-570 of 1146")
	)
	(layers
		(0 "F.Cu" signal "TOP")
		(4 "In1.Cu" signal "L2GND")
		(6 "In2.Cu" signal "L3")
		(8 "In3.Cu" signal "L4VCC")
		(10 "In4.Cu" signal "L5VCC")
		(12 "In5.Cu" signal "L6")
		(14 "In6.Cu" signal "L7GND")
		(2 "B.Cu" signal "BOTTOM")
		(9 "F.Adhes" user "F.Adhesive")
		(11 "B.Adhes" user "B.Adhesive")
		(13 "F.Paste" user "Package Geometry/Pastemask Top")
		(15 "B.Paste" user "Package Geometry/Pastemask Bottom")
		(5 "F.SilkS" user "Ref Des/Silkscreen Top")
		(7 "B.SilkS" user "Ref Des/Silkscreen Bottom")
		(1 "F.Mask" user "Board Geometry/Soldermask Top")
		(3 "B.Mask" user "Board Geometry/Soldermask Bottom")
		(17 "Dwgs.User" user "User.Drawings")
		(19 "Cmts.User" user "User.Comments")
		(21 "Eco1.User" user "User.Eco1")
		(23 "Eco2.User" user "User.Eco2")
		(25 "Edge.Cuts" user "Board Geometry/Outline")
		(27 "Margin" user)
		(31 "F.CrtYd" user "Package Geometry/Place Bound Top")
		(29 "B.CrtYd" user "Package Geometry/Place Bound Bottom")
		(35 "F.Fab" user "Ref Des/Assembly Top")
		(33 "B.Fab" user "Ref Des/Assembly Bottom")
	)
	(footprint ""
		(layer "F.Cu")
		(at 34.294826 -181.57063 -90)
		(property "Reference" "PU2"
			(at 0 0 270)
			(layer "F.SilkS")
			(hide yes)
			(effects
				(font
					(size 1.27 1.27)
				)
			)
		)
		(property "Value" "TPS53318DQPR-GP"
			(at -5.022088 -6.851904 270)
			(unlocked yes)
			(layer "F.Fab")
			(hide yes)
			(effects
				(font
					(size 1.016 1.016)
					(thickness 0.1524)
				)
			)
		)
		(property "Device Type" "DFN22G6050-G6133H60"
			(at -5.022088 -8.375904 270)
			(unlocked yes)
			(layer "F.Fab")
			(hide yes)
			(effects
				(font
					(size 1.016 1.016)
					(thickness 0.1524)
				)
			)
		)
		(duplicate_pad_numbers_are_jumpers no)
		(fp_line
			(start -3.5052 3.5179)
			(end -2.2352 3.5179)
			(stroke
				(width 0.1524)
				(type default)
			)
			(layer "F.SilkS")
		)
		(fp_line
			(start 2.2352 3.5179)
			(end 3.5052 3.5179)
			(stroke
				(width 0.1524)
				(type default)
			)
			(layer "F.SilkS")
		)
		(fp_line
			(start 3.5052 3.5179)
			(end 3.5052 2.2479)
			(stroke
				(width 0.1524)
				(type default)
			)
			(layer "F.SilkS")
		)
		(fp_line
			(start -0.999998 3.262122)
			(end -0.999998 3.770122)
			(stroke
				(width 0.1524)
				(type default)
			)
			(layer "F.SilkS")
		)
		(fp_line
			(start 1.500124 3.262122)
			(end 1.500124 4.024122)
			(stroke
				(width 0.1524)
				(type default)
			)
			(layer "F.SilkS")
		)
		(fp_line
			(start -3.5052 2.2479)
			(end -3.5052 3.5179)
			(stroke
				(width 0.1524)
				(type default)
			)
			(layer "F.SilkS")
		)
		(fp_line
			(start -1.999996 -3.262122)
			(end -1.999996 -4.024122)
			(stroke
				(width 0.1524)
				(type default)
			)
			(layer "F.SilkS")
		)
		(fp_line
			(start 0.500126 -3.262122)
			(end 0.500126 -3.770122)
			(stroke
				(width 0.1524)
				(type default)
			)
			(layer "F.SilkS")
		)
		(fp_line
			(start -3.5052 -3.5179)
			(end -3.5052 -2.2479)
			(stroke
				(width 0.1524)
				(type default)
			)
			(layer "F.SilkS")
		)
		(fp_line
			(start -2.2352 -3.5179)
			(end -3.5052 -3.5179)
			(stroke
				(width 0.1524)
				(type default)
			)
			(layer "F.SilkS")
		)
		(fp_poly
			(pts
				(xy 3.5052 -3.5179) (xy 2.4765 -3.5179) (xy 3.5052 -2.4892)
			)
			(stroke
				(width 0)
				(type default)
			)
			(fill yes)
			(layer "F.SilkS")
		)
		(fp_rect
			(start -2.9972 2.5019)
			(end 2.9972 -2.5019)
			(stroke
				(width 0)
				(type default)
			)
			(fill no)
			(layer "F.CrtYd")
		)
		(fp_poly
			(pts
				(xy 3.556 -2.5019) (xy -2.9972 -2.5019) (xy -2.9972 2.5019) (xy 2.9972 2.5019) (xy 2.9972 -2.4892)
				(xy 3.556 -2.4892) (xy 3.556 3.5179) (xy -3.556 3.5179) (xy -3.556 -3.5179) (xy 3.556 -3.5179)
			)
			(stroke
				(width 0)
				(type default)
			)
			(fill no)
			(layer "F.CrtYd")
		)
		(fp_rect
			(start -3.556 3.5179)
			(end 3.556 -3.5179)
			(stroke
				(width 0)
				(type default)
			)
			(fill no)
			(layer "F.Fab")
		)
		(pad "1" smd rect
			(at 2.500122 -2.449322 270)
			(size 0.3048 1.1176)
			(layers "F.Cu" "F.Mask" "F.Paste")
			(net "P3V3_STBY_VFB")
		)
		(pad "2" smd rect
			(at 1.999996 -2.449322 270)
			(size 0.3048 1.1176)
			(layers "F.Cu" "F.Mask" "F.Paste")
			(net "P3V3_STBY_EN")
		)
		(pad "3" smd rect
			(at 1.500124 -2.449322 270)
			(size 0.3048 1.1176)
			(layers "F.Cu" "F.Mask" "F.Paste")
			(net "PWRGD_P3V3_STBY")
		)
		(pad "4" smd rect
			(at 0.999998 -2.449322 270)
			(size 0.3048 1.1176)
			(layers "F.Cu" "F.Mask" "F.Paste")
			(net "P3V3_VBST")
		)
		(pad "5" smd rect
			(at 0.500126 -2.449322 270)
			(size 0.3048 1.1176)
			(layers "F.Cu" "F.Mask" "F.Paste")
			(net "P3V3_STBY_ROVP")
		)
		(pad "6" smd rect
			(at 0 -2.449322 270)
			(size 0.3048 1.1176)
			(layers "F.Cu" "F.Mask" "F.Paste")
			(net "P3V3_STBY_LL")
		)
		(pad "7" smd rect
			(at -0.500126 -2.449322 270)
			(size 0.3048 1.1176)
			(layers "F.Cu" "F.Mask" "F.Paste")
			(net "P3V3_STBY_LL")
		)
		(pad "8" smd rect
			(at -0.999998 -2.449322 270)
			(size 0.3048 1.1176)
			(layers "F.Cu" "F.Mask" "F.Paste")
			(net "P3V3_STBY_LL")
		)
		(pad "9" smd rect
			(at -1.500124 -2.449322 270)
			(size 0.3048 1.1176)
			(layers "F.Cu" "F.Mask" "F.Paste")
			(net "P3V3_STBY_LL")
		)
		(pad "10" smd rect
			(at -1.999996 -2.449322 270)
			(size 0.3048 1.1176)
			(layers "F.Cu" "F.Mask" "F.Paste")
			(net "P3V3_STBY_LL")
		)
		(pad "11" smd rect
			(at -2.500122 -2.449322 270)
			(size 0.3048 1.1176)
			(layers "F.Cu" "F.Mask" "F.Paste")
			(net "P3V3_STBY_LL")
		)
		(pad "12" smd rect
			(at -2.500122 2.449322 270)
			(size 0.3048 1.1176)
			(layers "F.Cu" "F.Mask" "F.Paste")
			(net "P12V_STBY_VIN_PU2")
		)
		(pad "13" smd rect
			(at -1.999996 2.449322 270)
			(size 0.3048 1.1176)
			(layers "F.Cu" "F.Mask" "F.Paste")
			(net "P12V_STBY_VIN_PU2")
		)
		(pad "14" smd rect
			(at -1.500124 2.449322 270)
			(size 0.3048 1.1176)
			(layers "F.Cu" "F.Mask" "F.Paste")
			(net "P12V_STBY_VIN_PU2")
		)
		(pad "15" smd rect
			(at -0.999998 2.449322 270)
			(size 0.3048 1.1176)
			(layers "F.Cu" "F.Mask" "F.Paste")
			(net "P12V_STBY_VIN_PU2")
		)
		(pad "16" smd rect
			(at -0.500126 2.449322 270)
			(size 0.3048 1.1176)
			(layers "F.Cu" "F.Mask" "F.Paste")
			(net "P12V_STBY_VIN_PU2")
		)
		(pad "17" smd rect
			(at 0 2.449322 270)
			(size 0.3048 1.1176)
			(layers "F.Cu" "F.Mask" "F.Paste")
			(net "P12V_STBY_VIN_PU2")
		)
		(pad "18" smd rect
			(at 0.500126 2.449322 270)
			(size 0.3048 1.1176)
			(layers "F.Cu" "F.Mask" "F.Paste")
			(net "P3V3_STBY_VREG")
		)
		(pad "19" smd rect
			(at 0.999998 2.449322 270)
			(size 0.3048 1.1176)
			(layers "F.Cu" "F.Mask" "F.Paste")
			(net "P12V_STBY_VDD_PU2")
		)
		(pad "20" smd rect
			(at 1.500124 2.449322 270)
			(size 0.3048 1.1176)
			(layers "F.Cu" "F.Mask" "F.Paste")
			(net "P3V3_STBY_MODE")
		)
		(pad "21" smd rect
			(at 1.999996 2.449322 270)
			(size 0.3048 1.1176)
			(layers "F.Cu" "F.Mask" "F.Paste")
			(net "P3V3_STBY_TRIP")
		)
		(pad "22" smd rect
			(at 2.500122 2.449322 270)
			(size 0.3048 1.1176)
			(layers "F.Cu" "F.Mask" "F.Paste")
			(net "P3V3_STBY_RF")
		)
		(pad "23" smd custom
			(at 0 0 270)
			(size 0.83185 0.83185)
			(layers "F.Cu" "F.Mask" "F.Paste")
			(net "GND")
			(options
				(clearance outline)
				(anchor circle)
			)
			(primitives
				(gr_poly
					(pts
						(xy -2.7813 1.6637) (xy -2.7813 1.2954) (xy -3.048 1.2954) (xy -3.048 0.9525) (xy -2.7813 0.9525)
						(xy -2.7813 -0.9525) (xy -3.048 -0.9525) (xy -3.048 -1.2954) (xy -2.7813 -1.2954) (xy -2.7813 -1.6637)
						(xy 2.7813 -1.6637) (xy 2.7813 -1.2954) (xy 3.048 -1.2954) (xy 3.048 -0.9525) (xy 2.7813 -0.9525)
						(xy 2.7813 0.9525) (xy 3.048 0.9525) (xy 3.048 1.2954) (xy 2.7813 1.2954) (xy 2.7813 1.6637)
					)
					(width 0)
					(fill yes)
				)
			)
		)
	)
	(footprint ""
		(layer "F.Cu")
		(at 110.75797 -11.974576 -90)
		(property "Reference" "C147"
			(at 0 0 270)
			(layer "F.SilkS")
			(hide yes)
			(effects
				(font
					(size 1.27 1.27)
				)
			)
		)
		(property "Value" "SC1U16V3KX-5GP"
			(at 0 -2.8194 270)
			(unlocked yes)
			(layer "F.Fab")
			(hide yes)
			(effects
				(font
					(size 1.016 1.016)
					(thickness 0.1524)
				)
			)
		)
		(property "Device Type" "C603H36"
			(at 0 -4.3434 270)
			(unlocked yes)
			(layer "F.Fab")
			(hide yes)
			(effects
				(font
					(size 1.016 1.016)
					(thickness 0.1524)
				)
			)
		)
		(duplicate_pad_numbers_are_jumpers no)
		(fp_line
			(start 0.508 0)
			(end -0.508 0)
			(stroke
				(width 0.2032)
				(type default)
			)
			(layer "F.SilkS")
		)
		(fp_rect
			(start -0.5842 1.3335)
			(end 0.5842 -1.3335)
			(stroke
				(width 0)
				(type default)
			)
			(fill no)
			(layer "F.CrtYd")
		)
		(fp_rect
			(start -0.5842 1.3335)
			(end 0.5842 -1.3335)
			(stroke
				(width 0)
				(type default)
			)
			(fill no)
			(layer "F.Fab")
		)
		(pad "1" smd custom
			(at 0 -0.762 270)
			(size 0.2159 0.2159)
			(layers "F.Cu" "F.Mask" "F.Paste")
			(net "MB0_VCAP_R")
			(options
				(clearance outline)
				(anchor circle)
			)
			(primitives
				(gr_poly
					(pts
						(arc
							(start -0.3302 -0.4318)
							(mid -0.402042 -0.402042)
							(end -0.4318 -0.3302)
						)
						(arc
							(start -0.4318 0.3302)
							(mid -0.402042 0.402042)
							(end -0.3302 0.4318)
						)
						(arc
							(start 0.3302 0.4318)
							(mid 0.402042 0.402042)
							(end 0.4318 0.3302)
						)
						(arc
							(start 0.4318 -0.3302)
							(mid 0.402042 -0.402042)
							(end 0.3302 -0.4318)
						)
					)
					(width 0)
					(fill yes)
				)
			)
		)
		(pad "2" smd custom
			(at 0 0.762 270)
			(size 0.2159 0.2159)
			(layers "F.Cu" "F.Mask" "F.Paste")
			(net "AGND_CURRENT_MON")
			(options
				(clearance outline)
				(anchor circle)
			)
			(primitives
				(gr_poly
					(pts
						(arc
							(start -0.3302 -0.4318)
							(mid -0.402042 -0.402042)
							(end -0.4318 -0.3302)
						)
						(arc
							(start -0.4318 0.3302)
							(mid -0.402042 0.402042)
							(end -0.3302 0.4318)
						)
						(arc
							(start 0.3302 0.4318)
							(mid 0.402042 0.402042)
							(end 0.4318 0.3302)
						)
						(arc
							(start 0.4318 -0.3302)
							(mid 0.402042 -0.402042)
							(end 0.3302 -0.4318)
						)
					)
					(width 0)
					(fill yes)
				)
			)
		)
	)
	(footprint ""
		(layer "F.Cu")
		(at 60.375546 -185.000138 -90)
		(property "Reference" "R480"
			(at 0 0 270)
			(layer "F.SilkS")
			(hide yes)
			(effects
				(font
					(size 1.27 1.27)
				)
			)
		)
		(property "Value" "0R6J-3-GP"
			(at -0.0508 -4.8514 270)
			(unlocked yes)
			(layer "F.Fab")
			(hide yes)
			(effects
				(font
					(size 1.016 1.016)
					(thickness 0.1524)
				)
			)
		)
		(property "Device Type" "R1206H28"
			(at 0 -6.3754 270)
			(unlocked yes)
			(layer "F.Fab")
			(hide yes)
			(effects
				(font
					(size 1.016 1.016)
					(thickness 0.1524)
				)
			)
		)
		(duplicate_pad_numbers_are_jumpers no)
		(fp_line
			(start -1.016 2.2352)
			(end -1.016 -2.2352)
			(stroke
				(width 0.1524)
				(type default)
			)
			(layer "F.SilkS")
		)
		(fp_line
			(start 1.016 2.2352)
			(end -1.016 2.2352)
			(stroke
				(width 0.1524)
				(type default)
			)
			(layer "F.SilkS")
		)
		(fp_line
			(start -1.016 -2.2352)
			(end 1.016 -2.2352)
			(stroke
				(width 0.1524)
				(type default)
			)
			(layer "F.SilkS")
		)
		(fp_line
			(start 1.016 -2.2352)
			(end 1.016 2.2352)
			(stroke
				(width 0.1524)
				(type default)
			)
			(layer "F.SilkS")
		)
		(fp_rect
			(start -1.0922 2.3114)
			(end 1.0922 -2.3114)
			(stroke
				(width 0)
				(type default)
			)
			(fill no)
			(layer "F.CrtYd")
		)
		(fp_poly
			(pts
				(xy -1.0922 -2.3114) (xy 1.0922 -2.3114) (xy 1.0922 2.3114) (xy -1.0922 2.3114)
			)
			(stroke
				(width 0)
				(type default)
			)
			(fill no)
			(layer "F.Fab")
		)
		(pad "1" smd rect
			(at 0 -1.397 270)
			(size 1.651 1.27)
			(layers "F.Cu" "F.Mask" "F.Paste")
			(net "P3V3_STBY")
		)
		(pad "2" smd rect
			(at 0 1.397 270)
			(size 1.651 1.27)
			(layers "F.Cu" "F.Mask" "F.Paste")
			(net "P3V3_STBY_OUT")
		)
	)
	(footprint ""
		(layer "F.Cu")
		(at 91.72448 -149.196044)
		(property "Reference" "R25"
			(at 0 0 0)
			(layer "F.SilkS")
			(hide yes)
			(effects
				(font
					(size 1.27 1.27)
				)
			)
		)
		(property "Value" "15KR2F-GP"
			(at 0.064008 -3.993896 0)
			(unlocked yes)
			(layer "F.Fab")
			(hide yes)
			(effects
				(font
					(size 1.016 1.016)
					(thickness 0.1524)
				)
			)
		)
		(property "Device Type" "R402H16"
			(at 0.064008 -5.517896 0)
			(unlocked yes)
			(layer "F.Fab")
			(hide yes)
			(effects
				(font
					(size 1.016 1.016)
					(thickness 0.1524)
				)
			)
		)
		(duplicate_pad_numbers_are_jumpers no)
		(fp_line
			(start -0.508 -0.9398)
			(end -0.508 0.9398)
			(stroke
				(width 0.1524)
				(type default)
			)
			(layer "F.SilkS")
		)
		(fp_line
			(start 0.508 -0.9398)
			(end -0.508 -0.9398)
			(stroke
				(width 0.1524)
				(type default)
			)
			(layer "F.SilkS")
		)
		(fp_rect
			(start -0.508 0.9398)
			(end 0.508 -0.9398)
			(stroke
				(width 0)
				(type default)
			)
			(fill no)
			(layer "F.CrtYd")
		)
		(fp_rect
			(start -0.508 0.9398)
			(end 0.508 -0.9398)
			(stroke
				(width 0)
				(type default)
			)
			(fill no)
			(layer "F.Fab")
		)
		(pad "1" smd custom
			(at 0 -0.4445)
			(size 0.1397 0.1397)
			(layers "F.Cu" "F.Mask" "F.Paste")
			(net "USB_OCS_N1")
			(options
				(clearance outline)
				(anchor circle)
			)
			(primitives
				(gr_poly
					(pts
						(arc
							(start -0.1778 -0.2794)
							(mid -0.249642 -0.249642)
							(end -0.2794 -0.1778)
						)
						(arc
							(start -0.2794 0.1778)
							(mid -0.249642 0.249642)
							(end -0.1778 0.2794)
						)
						(arc
							(start 0.1778 0.2794)
							(mid 0.249642 0.249642)
							(end 0.2794 0.1778)
						)
						(arc
							(start 0.2794 -0.1778)
							(mid 0.249642 -0.249642)
							(end 0.1778 -0.2794)
						)
					)
					(width 0)
					(fill yes)
				)
			)
		)
		(pad "2" smd custom
			(at 0 0.4445)
			(size 0.1397 0.1397)
			(layers "F.Cu" "F.Mask" "F.Paste")
			(net "GND")
			(options
				(clearance outline)
				(anchor circle)
			)
			(primitives
				(gr_poly
					(pts
						(arc
							(start -0.1778 -0.2794)
							(mid -0.249642 -0.249642)
							(end -0.2794 -0.1778)
						)
						(arc
							(start -0.2794 0.1778)
							(mid -0.249642 0.249642)
							(end -0.1778 0.2794)
						)
						(arc
							(start 0.1778 0.2794)
							(mid 0.249642 0.249642)
							(end 0.2794 0.1778)
						)
						(arc
							(start 0.2794 -0.1778)
							(mid 0.249642 -0.249642)
							(end 0.1778 -0.2794)
						)
					)
					(width 0)
					(fill yes)
				)
			)
		)
	)
	(footprint ""
		(layer "F.Cu")
		(at 97.6122 -139.7254)
		(property "Reference" "R276"
			(at 0 0 0)
			(layer "F.SilkS")
			(hide yes)
			(effects
				(font
					(size 1.27 1.27)
				)
			)
		)
		(property "Value" "4K7R2F-GP"
			(at 0.064008 -3.993896 0)
			(unlocked yes)
			(layer "F.Fab")
			(hide yes)
			(effects
				(font
					(size 1.016 1.016)
					(thickness 0.1524)
				)
			)
		)
		(property "Device Type" "R402H16"
			(at 0.064008 -5.517896 0)
			(unlocked yes)
			(layer "F.Fab")
			(hide yes)
			(effects
				(font
					(size 1.016 1.016)
					(thickness 0.1524)
				)
			)
		)
		(duplicate_pad_numbers_are_jumpers no)
		(fp_line
			(start -0.508 -0.9398)
			(end -0.508 0.9398)
			(stroke
				(width 0.1524)
				(type default)
			)
			(layer "F.SilkS")
		)
		(fp_line
			(start 0.508 -0.9398)
			(end -0.508 -0.9398)
			(stroke
				(width 0.1524)
				(type default)
			)
			(layer "F.SilkS")
		)
		(fp_rect
			(start -0.508 0.9398)
			(end 0.508 -0.9398)
			(stroke
				(width 0)
				(type default)
			)
			(fill no)
			(layer "F.CrtYd")
		)
		(fp_rect
			(start -0.508 0.9398)
			(end 0.508 -0.9398)
			(stroke
				(width 0)
				(type default)
			)
			(fill no)
			(layer "F.Fab")
		)
		(pad "1" smd custom
			(at 0 -0.4445)
			(size 0.1397 0.1397)
			(layers "F.Cu" "F.Mask" "F.Paste")
			(net "P3V3_STBY")
			(options
				(clearance outline)
				(anchor circle)
			)
			(primitives
				(gr_poly
					(pts
						(arc
							(start -0.1778 -0.2794)
							(mid -0.249642 -0.249642)
							(end -0.2794 -0.1778)
						)
						(arc
							(start -0.2794 0.1778)
							(mid -0.249642 0.249642)
							(end -0.1778 0.2794)
						)
						(arc
							(start 0.1778 0.2794)
							(mid 0.249642 0.249642)
							(end 0.2794 0.1778)
						)
						(arc
							(start 0.2794 -0.1778)
							(mid 0.249642 -0.249642)
							(end 0.1778 -0.2794)
						)
					)
					(width 0)
					(fill yes)
				)
			)
		)
		(pad "2" smd custom
			(at 0 0.4445)
			(size 0.1397 0.1397)
			(layers "F.Cu" "F.Mask" "F.Paste")
			(net "DEBUG_RST_BTN_N")
			(options
				(clearance outline)
				(anchor circle)
			)
			(primitives
				(gr_poly
					(pts
						(arc
							(start -0.1778 -0.2794)
							(mid -0.249642 -0.249642)
							(end -0.2794 -0.1778)
						)
						(arc
							(start -0.2794 0.1778)
							(mid -0.249642 0.249642)
							(end -0.1778 0.2794)
						)
						(arc
							(start 0.1778 0.2794)
							(mid 0.249642 0.249642)
							(end 0.2794 0.1778)
						)
						(arc
							(start 0.2794 -0.1778)
							(mid 0.249642 -0.249642)
							(end 0.1778 -0.2794)
						)
					)
					(width 0)
					(fill yes)
				)
			)
		)
	)
)
